# TIMECARD (Time Appliance Project (Time Card)) — schematic netlist excerpt (pin names and nets, part order shuffled) for the footprints in the layout excerpt that follows; sources: Cadence DE-HDL packaged netlist, KiCad conversion of R4006-B0001-02_R01.brd

J18  CONN_HDR_1X3_M_S_SMT  pkg S_M_H_3P_S_P058  page 21
  \1\  = SG
  \2\  = SMA_ANALOG_TUNING_IN
  \3\  = SG

(kicad_pcb
	(version 20260206)
	(generator "pcbnew")
	(generator_version "10.0")
	(general
		(thickness 1.6)
		(legacy_teardrops no)
	)
	(paper "A4")
	(title_block
		(title "timecard-production-celestica-r4006 — R4006-B0001-02_R01.brd")
		(comment 1 "Time Appliance Project (Time Card) / footprints 522-522 of 1113")
	)
	(layers
		(0 "F.Cu" signal "TOP")
		(4 "In1.Cu" signal "L02_GND1")
		(6 "In2.Cu" signal "L03_SIG1")
		(8 "In3.Cu" signal "L04_GND2")
		(10 "In4.Cu" signal "L05_VCC1")
		(12 "In5.Cu" signal "L06_VCC2")
		(14 "In6.Cu" signal "L07_GND3")
		(16 "In7.Cu" signal "L08_SIG2")
		(18 "In8.Cu" signal "L09_GND4")
		(2 "B.Cu" signal "BOTTOM")
		(9 "F.Adhes" user "F.Adhesive")
		(11 "B.Adhes" user "B.Adhesive")
		(13 "F.Paste" user "Package Geometry/Pastemask Top")
		(15 "B.Paste" user "Package Geometry/Pastemask Bottom")
		(5 "F.SilkS" user "Ref Des/Silkscreen Top")
		(7 "B.SilkS" user "Ref Des/Silkscreen Bottom")
		(1 "F.Mask" user "Board Geometry/Soldermask Top")
		(3 "B.Mask" user "Board Geometry/Soldermask Bottom")
		(17 "Dwgs.User" user "User.Drawings")
		(19 "Cmts.User" user "User.Comments")
		(21 "Eco1.User" user "User.Eco1")
		(23 "Eco2.User" user "User.Eco2")
		(25 "Edge.Cuts" user "Board Geometry/Outline")
		(27 "Margin" user)
		(31 "F.CrtYd" user "Package Geometry/Place Bound Top")
		(29 "B.CrtYd" user "Package Geometry/Place Bound Bottom")
		(35 "F.Fab" user "Ref Des/Assembly Top")
		(33 "B.Fab" user "Ref Des/Assembly Bottom")
	)
	(footprint ""
		(layer "F.Cu")
		(at 20.4216 -53.1114 180)
		(property "Reference" "J18"
			(at -3.5814 0.31623 0)
			(unlocked yes)
			(layer "F.SilkS")
			(effects
				(font
					(size 0.7874 0.5842)
					(thickness 0.1524)
				)
			)
		)
		(property "Value" ""
			(at 0 0 180)
			(layer "F.Fab")
			(effects
				(font
					(size 1.27 1.27)
				)
			)
		)
		(property "User Part Number" "PARTNUM*"
			(at 0.126238 5.484368 180)
			(unlocked yes)
			(layer "Cmts.User")
			(hide yes)
			(effects
				(font
					(size 0.7874 0.5842)
					(thickness 0.1524)
				)
			)
		)
		(property "Device Type" "CONN_HDR_1X3_M_S_SMT-G205-1002A"
			(at 0.126238 4.290568 180)
			(unlocked yes)
			(layer "F.Fab")
			(hide yes)
			(effects
				(font
					(size 0.7874 0.5842)
					(thickness 0.1524)
				)
			)
		)
		(duplicate_pad_numbers_are_jumpers no)
		(fp_line
			(start 2.249678 2.299716)
			(end -2.249678 2.299716)
			(stroke
				(width 0.1)
				(type default)
			)
			(layer "F.SilkS")
		)
		(fp_line
			(start 2.249678 -1.67894)
			(end 2.249678 2.299716)
			(stroke
				(width 0.1)
				(type default)
			)
			(layer "F.SilkS")
		)
		(fp_line
			(start -2.249678 2.299716)
			(end -2.249678 -1.67894)
			(stroke
				(width 0.1)
				(type default)
			)
			(layer "F.SilkS")
		)
		(fp_line
			(start -2.249678 -1.67894)
			(end 2.249678 -1.67894)
			(stroke
				(width 0.1)
				(type default)
			)
			(layer "F.SilkS")
		)
		(fp_rect
			(start -2.503678 2.553716)
			(end 2.503678 -1.93294)
			(stroke
				(width 0)
				(type default)
			)
			(fill no)
			(layer "F.CrtYd")
		)
		(fp_line
			(start 1.42494 1.42494)
			(end 0.374904 1.42494)
			(stroke
				(width 0.1)
				(type default)
			)
			(layer "F.Fab")
		)
		(fp_line
			(start 1.42494 -1.42494)
			(end 1.42494 1.42494)
			(stroke
				(width 0.1)
				(type default)
			)
			(layer "F.Fab")
		)
		(fp_line
			(start 0.374904 1.674876)
			(end -0.374904 1.674876)
			(stroke
				(width 0.1)
				(type default)
			)
			(layer "F.Fab")
		)
		(fp_line
			(start 0.374904 1.42494)
			(end 0.374904 1.674876)
			(stroke
				(width 0.1)
				(type default)
			)
			(layer "F.Fab")
		)
		(fp_line
			(start -0.374904 1.674876)
			(end -0.374904 1.42494)
			(stroke
				(width 0.1)
				(type default)
			)
			(layer "F.Fab")
		)
		(fp_line
			(start -0.374904 1.42494)
			(end -1.42494 1.42494)
			(stroke
				(width 0.1)
				(type default)
			)
			(layer "F.Fab")
		)
		(fp_line
			(start -1.42494 1.42494)
			(end -1.42494 -1.42494)
			(stroke
				(width 0.1)
				(type default)
			)
			(layer "F.Fab")
		)
		(fp_line
			(start -1.42494 -1.42494)
			(end 1.42494 -1.42494)
			(stroke
				(width 0.1)
				(type default)
			)
			(layer "F.Fab")
		)
		(fp_text user "3"
			(at 2.6416 -0.69215 0)
			(unlocked yes)
			(layer "F.SilkS")
			(effects
				(font
					(size 0.635 0.4064)
					(thickness 0.1524)
				)
			)
		)
		(fp_text user "2"
			(at -2.5654 1.97485 0)
			(unlocked yes)
			(layer "F.SilkS")
			(effects
				(font
					(size 0.635 0.4064)
					(thickness 0.1524)
				)
			)
		)
		(fp_text user "1"
			(at -2.9464 -0.89535 0)
			(unlocked yes)
			(layer "F.SilkS")
			(effects
				(font
					(size 0.635 0.4064)
					(thickness 0.1524)
				)
			)
		)
		(fp_text user "3"
			(at 2.2606 0.96393 0)
			(unlocked yes)
			(layer "F.Fab")
			(effects
				(font
					(size 0.7874 0.5842)
					(thickness 0.1524)
				)
			)
		)
		(fp_text user "2"
			(at -1.0414 2.22123 0)
			(unlocked yes)
			(layer "F.Fab")
			(effects
				(font
					(size 0.7874 0.5842)
					(thickness 0.1524)
				)
			)
		)
		(fp_text user "1"
			(at -2.1844 0.07493 0)
			(unlocked yes)
			(layer "F.Fab")
			(effects
				(font
					(size 0.7874 0.5842)
					(thickness 0.1524)
				)
			)
		)
		(pad "1" smd rect
			(at -1.474978 0 180)
			(size 1.0414 2.2098)
			(layers "F.Cu" "F.Mask" "F.Paste")
			(net "SG")
		)
		(pad "2" smd rect
			(at 0 1.525016 180)
			(size 0.9906 1.0414)
			(layers "F.Cu" "F.Mask" "F.Paste")
			(net "SMA_ANALOG_TUNING_IN")
		)
		(pad "3" smd rect
			(at 1.474978 0 180)
			(size 1.0414 2.2098)
			(layers "F.Cu" "F.Mask" "F.Paste")
			(net "SG")
		)
	)
)
